(kicad_pcb
	(version 20260206)
	(generator "pcbnew")
	(generator_version "10.0")
	(general
		(thickness 1.6)
		(legacy_teardrops no)
	)
	(paper "A4")
	(title_block
		(title "peb — Lightning_PEB_BRD.brd")
		(comment 1 "Lightning (Wiwynn / Facebook NVMe JBOF) / footprints 306-312 of 2563")
	)
	(layers
		(0 "F.Cu" signal "TOP")
		(4 "In1.Cu" signal "L2GND")
		(6 "In2.Cu" signal "L3")
		(8 "In3.Cu" signal "L4VCC")
		(10 "In4.Cu" signal "L5VCC")
		(12 "In5.Cu" signal "L6")
		(14 "In6.Cu" signal "L7GND")
		(2 "B.Cu" signal "BOTTOM")
		(9 "F.Adhes" user "F.Adhesive")
		(11 "B.Adhes" user "B.Adhesive")
		(13 "F.Paste" user "Package Geometry/Pastemask Top")
		(15 "B.Paste" user "Package Geometry/Pastemask Bottom")
		(5 "F.SilkS" user "Ref Des/Silkscreen Top")
		(7 "B.SilkS" user "Ref Des/Silkscreen Bottom")
		(1 "F.Mask" user "Board Geometry/Soldermask Top")
		(3 "B.Mask" user "Board Geometry/Soldermask Bottom")
		(17 "Dwgs.User" user "User.Drawings")
		(19 "Cmts.User" user "User.Comments")
		(21 "Eco1.User" user "User.Eco1")
		(23 "Eco2.User" user "User.Eco2")
		(25 "Edge.Cuts" user "Board Geometry/Outline")
		(27 "Margin" user)
		(31 "F.CrtYd" user "Package Geometry/Place Bound Top")
		(29 "B.CrtYd" user "Package Geometry/Place Bound Bottom")
		(35 "F.Fab" user "Ref Des/Assembly Top")
		(33 "B.Fab" user "Ref Des/Assembly Bottom")
	)
	(footprint ""
		(layer "F.Cu")
		(at 81.364836 -67.109594)
		(property "Reference" "SKT5"
			(at 0 0 0)
			(layer "F.SilkS")
			(hide yes)
			(effects
				(font
					(size 1.27 1.27)
				)
			)
		)
		(property "Value" "SKT-SPI16P-GP-U"
			(at -8.9916 4.641596 0)
			(unlocked yes)
			(layer "F.Fab")
			(hide yes)
			(effects
				(font
					(size 1.016 1.016)
					(thickness 0.1524)
				)
			)
		)
		(property "Device Type" "SKT-SOIC16-153139H258"
			(at -8.9916 3.117596 0)
			(unlocked yes)
			(layer "F.Fab")
			(hide yes)
			(effects
				(font
					(size 1.016 1.016)
					(thickness 0.1524)
				)
			)
		)
		(duplicate_pad_numbers_are_jumpers no)
		(fp_line
			(start -7.8994 -6.4008)
			(end -7.8994 6.4008)
			(stroke
				(width 0.1524)
				(type default)
			)
			(layer "F.SilkS")
		)
		(fp_line
			(start -7.8994 6.4008)
			(end 7.8994 6.4008)
			(stroke
				(width 0.1524)
				(type default)
			)
			(layer "F.SilkS")
		)
		(fp_line
			(start 6.7183 0.0762)
			(end 7.8994 1.2573)
			(stroke
				(width 0.1524)
				(type default)
			)
			(layer "F.SilkS")
		)
		(fp_line
			(start 7.7216 -6.223)
			(end 7.7216 -3.6576)
			(stroke
				(width 0.508)
				(type default)
			)
			(layer "F.SilkS")
		)
		(fp_line
			(start 7.8867 -1.0922)
			(end 6.7183 0.0762)
			(stroke
				(width 0.1524)
				(type default)
			)
			(layer "F.SilkS")
		)
		(fp_line
			(start 7.8994 -6.4008)
			(end -7.8994 -6.4008)
			(stroke
				(width 0.1524)
				(type default)
			)
			(layer "F.SilkS")
		)
		(fp_line
			(start 7.8994 6.4008)
			(end 7.8994 -6.4008)
			(stroke
				(width 0.1524)
				(type default)
			)
			(layer "F.SilkS")
		)
		(fp_poly
			(pts
				(xy -4.699 -3.855466) (xy -4.699 3.855466) (xy 4.699 3.855466) (xy 4.699 -3.855466)
			)
			(stroke
				(width 0)
				(type default)
			)
			(fill yes)
			(layer "F.SilkS")
		)
		(fp_rect
			(start -8.1534 -6.4008)
			(end 8.1534 -12.5222)
			(stroke
				(width 0)
				(type default)
			)
			(fill no)
			(layer "F.CrtYd")
		)
		(fp_rect
			(start -8.1534 11.6078)
			(end 8.1534 6.4008)
			(stroke
				(width 0)
				(type default)
			)
			(fill no)
			(layer "F.CrtYd")
		)
		(fp_poly
			(pts
				(xy -8.1534 6.4008) (xy -8.1534 -6.4008) (xy -6.2484 -6.4008) (xy -6.2484 -2.6416) (xy -7.6454 -2.6416)
				(xy -7.6454 2.6416) (xy -6.2484 2.6416) (xy -6.2484 6.4008)
			)
			(stroke
				(width 0)
				(type default)
			)
			(fill no)
			(layer "F.CrtYd")
		)
		(fp_poly
			(pts
				(xy 6.2484 -6.4008) (xy 8.1534 -6.4008) (xy 8.1534 6.4008) (xy 6.2484 6.4008) (xy 6.2484 2.6416)
				(xy 7.6454 2.6416) (xy 7.6454 -2.6416) (xy 6.2484 -2.6416)
			)
			(stroke
				(width 0)
				(type default)
			)
			(fill no)
			(layer "F.CrtYd")
		)
		(fp_poly
			(pts
				(xy 6.2484 -6.4008) (xy -6.2484 -6.4008) (xy -6.2484 -2.6416) (xy -7.6454 -2.6416) (xy -7.6454 2.6416)
				(xy -6.2484 2.6416) (xy -6.2484 6.4008) (xy 6.2484 6.4008) (xy 6.2484 2.6416) (xy 7.6454 2.6416)
				(xy 7.6454 -2.6416) (xy 6.2484 -2.6416)
			)
			(stroke
				(width 0)
				(type default)
			)
			(fill no)
			(layer "F.CrtYd")
		)
		(fp_rect
			(start -8.1534 11.6078)
			(end 8.1534 -12.5222)
			(stroke
				(width 0)
				(type default)
			)
			(fill no)
			(layer "F.Fab")
		)
		(pad "1" smd rect
			(at 4.445 -4.896866)
			(size 0.508 1.6764)
			(layers "F.Cu" "F.Mask" "F.Paste")
			(net "SEC_SPI_HOLD_N")
		)
		(pad "2" smd rect
			(at 3.175 -4.896866)
			(size 0.508 1.6764)
			(layers "F.Cu" "F.Mask" "F.Paste")
			(net "P3V3_STBY")
		)
		(pad "3" smd rect
			(at 1.905 -4.896866)
			(size 0.508 1.6764)
			(layers "F.Cu" "F.Mask" "F.Paste")
			(net "SEC_RST_N_R")
		)
		(pad "4" smd rect
			(at 0.635 -4.896866)
			(size 0.508 1.6764)
			(layers "F.Cu" "F.Mask" "F.Paste")
			(net "Net_288")
		)
		(pad "5" smd rect
			(at -0.635 -4.896866)
			(size 0.508 1.6764)
			(layers "F.Cu" "F.Mask" "F.Paste")
			(net "Net_287")
		)
		(pad "6" smd rect
			(at -1.905 -4.896866)
			(size 0.508 1.6764)
			(layers "F.Cu" "F.Mask" "F.Paste")
			(net "Net_286")
		)
		(pad "7" smd rect
			(at -3.175 -4.896866)
			(size 0.508 1.6764)
			(layers "F.Cu" "F.Mask" "F.Paste")
			(net "FLA_CS_R")
		)
		(pad "8" smd rect
			(at -4.445 -4.896866)
			(size 0.508 1.6764)
			(layers "F.Cu" "F.Mask" "F.Paste")
			(net "ROMD2_SEC")
		)
		(pad "9" smd rect
			(at -4.445 4.896866)
			(size 0.508 1.6764)
			(layers "F.Cu" "F.Mask" "F.Paste")
			(net "FLA1_WPN")
		)
		(pad "10" smd rect
			(at -3.175 4.896866)
			(size 0.508 1.6764)
			(layers "F.Cu" "F.Mask" "F.Paste")
			(net "GND")
		)
		(pad "11" smd rect
			(at -1.905 4.896866)
			(size 0.508 1.6764)
			(layers "F.Cu" "F.Mask" "F.Paste")
			(net "Net_292")
		)
		(pad "12" smd rect
			(at -0.635 4.896866)
			(size 0.508 1.6764)
			(layers "F.Cu" "F.Mask" "F.Paste")
			(net "Net_291")
		)
		(pad "13" smd rect
			(at 0.635 4.896866)
			(size 0.508 1.6764)
			(layers "F.Cu" "F.Mask" "F.Paste")
			(net "Net_290")
		)
		(pad "14" smd rect
			(at 1.905 4.896866)
			(size 0.508 1.6764)
			(layers "F.Cu" "F.Mask" "F.Paste")
			(net "Net_289")
		)
		(pad "15" smd rect
			(at 3.175 4.896866)
			(size 0.508 1.6764)
			(layers "F.Cu" "F.Mask" "F.Paste")
			(net "ROMD1_R")
		)
		(pad "16" smd rect
			(at 4.445 4.896866)
			(size 0.508 1.6764)
			(layers "F.Cu" "F.Mask" "F.Paste")
			(net "ROMD0_R")
		)
	)
	(footprint ""
		(layer "F.Cu")
		(at 30.544008 -112.281208 180)
		(property "Reference" "R731"
			(at 0 0 180)
			(layer "F.SilkS")
			(hide yes)
			(effects
				(font
					(size 1.27 1.27)
				)
			)
		)
		(property "Value" "0R2J-2-GP"
			(at 0.064008 -3.993896 180)
			(unlocked yes)
			(layer "F.Fab")
			(hide yes)
			(effects
				(font
					(size 1.016 1.016)
					(thickness 0.1524)
				)
			)
		)
		(property "Device Type" "R402H16"
			(at 0.064008 -5.517896 180)
			(unlocked yes)
			(layer "F.Fab")
			(hide yes)
			(effects
				(font
					(size 1.016 1.016)
					(thickness 0.1524)
				)
			)
		)
		(duplicate_pad_numbers_are_jumpers no)
		(fp_line
			(start 0.508 -0.9398)
			(end -0.508 -0.9398)
			(stroke
				(width 0.1524)
				(type default)
			)
			(layer "F.SilkS")
		)
		(fp_line
			(start -0.508 -0.9398)
			(end -0.508 0.9398)
			(stroke
				(width 0.1524)
				(type default)
			)
			(layer "F.SilkS")
		)
		(fp_rect
			(start -0.508 0.9398)
			(end 0.508 -0.9398)
			(stroke
				(width 0)
				(type default)
			)
			(fill no)
			(layer "F.CrtYd")
		)
		(fp_rect
			(start -0.508 0.9398)
			(end 0.508 -0.9398)
			(stroke
				(width 0)
				(type default)
			)
			(fill no)
			(layer "F.Fab")
		)
		(pad "1" smd custom
			(at 0 -0.4445 180)
			(size 0.1397 0.1397)
			(layers "F.Cu" "F.Mask" "F.Paste")
			(net "LAN_SMB_ALERT_N")
			(options
				(clearance outline)
				(anchor circle)
			)
			(primitives
				(gr_poly
					(pts
						(arc
							(start -0.1778 -0.2794)
							(mid -0.249642 -0.249642)
							(end -0.2794 -0.1778)
						)
						(arc
							(start -0.2794 0.1778)
							(mid -0.249642 0.249642)
							(end -0.1778 0.2794)
						)
						(arc
							(start 0.1778 0.2794)
							(mid 0.249642 0.249642)
							(end 0.2794 0.1778)
						)
						(arc
							(start 0.2794 -0.1778)
							(mid 0.249642 -0.249642)
							(end 0.1778 -0.2794)
						)
					)
					(width 0)
					(fill yes)
				)
			)
		)
		(pad "2" smd custom
			(at 0 0.4445 180)
			(size 0.1397 0.1397)
			(layers "F.Cu" "F.Mask" "F.Paste")
			(net "LAN_SMB_ALERT_N_R")
			(options
				(clearance outline)
				(anchor circle)
			)
			(primitives
				(gr_poly
					(pts
						(arc
							(start -0.1778 -0.2794)
							(mid -0.249642 -0.249642)
							(end -0.2794 -0.1778)
						)
						(arc
							(start -0.2794 0.1778)
							(mid -0.249642 0.249642)
							(end -0.1778 0.2794)
						)
						(arc
							(start 0.1778 0.2794)
							(mid 0.249642 0.249642)
							(end 0.2794 0.1778)
						)
						(arc
							(start 0.2794 -0.1778)
							(mid 0.249642 -0.249642)
							(end 0.1778 -0.2794)
						)
					)
					(width 0)
					(fill yes)
				)
			)
		)
	)
	(footprint ""
		(layer "F.Cu")
		(at 167.6654 -87.5284 90)
		(property "Reference" "TP71"
			(at 0 0 90)
			(layer "F.SilkS")
			(hide yes)
			(effects
				(font
					(size 1.27 1.27)
				)
			)
		)
		(property "Value" "TPAD28-2-GP"
			(at -0.0127 -1.6637 90)
			(unlocked yes)
			(layer "F.Fab")
			(hide yes)
			(effects
				(font
					(size 1.016 1.016)
					(thickness 0.1524)
				)
			)
		)
		(property "Device Type" "TPAD28"
			(at -0.0127 -3.1877 90)
			(unlocked yes)
			(layer "F.Fab")
			(hide yes)
			(effects
				(font
					(size 1.016 1.016)
					(thickness 0.1524)
				)
			)
		)
		(duplicate_pad_numbers_are_jumpers no)
		(fp_poly
			(pts
				(arc
					(start 0 0.3556)
					(mid 0 -0.3556)
					(end 0 0.3556)
				)
			)
			(stroke
				(width 0)
				(type default)
			)
			(fill no)
			(layer "F.CrtYd")
		)
		(fp_poly
			(pts
				(arc
					(start 0 0.6096)
					(mid 0 -0.6096)
					(end 0 0.6096)
				)
			)
			(stroke
				(width 0)
				(type default)
			)
			(fill no)
			(layer "F.Fab")
		)
		(pad "1" smd circle
			(at 0 0 90)
			(size 0.7112 0.7112)
			(layers "F.Cu" "F.Mask" "F.Paste")
			(net "CLKGEN_OE1")
		)
	)
	(footprint ""
		(layer "F.Cu")
		(at 226.695 -5.842)
		(property "Reference" "LED14"
			(at 0 0 0)
			(layer "F.SilkS")
			(hide yes)
			(effects
				(font
					(size 1.27 1.27)
				)
			)
		)
		(property "Value" "LED-Y-11-GP"
			(at -0.1016 -8.1788 0)
			(unlocked yes)
			(layer "F.Fab")
			(hide yes)
			(effects
				(font
					(size 1.016 1.016)
					(thickness 0.1524)
				)
			)
		)
		(property "Device Type" "19-21UBC-1"
			(at -0.0508 -9.8552 0)
			(unlocked yes)
			(layer "F.Fab")
			(hide yes)
			(effects
				(font
					(size 1.016 1.016)
					(thickness 0.1524)
				)
			)
		)
		(duplicate_pad_numbers_are_jumpers no)
		(fp_line
			(start -1.7653 -0.7747)
			(end -1.7653 0.7747)
			(stroke
				(width 0.508)
				(type default)
			)
			(layer "F.SilkS")
		)
		(fp_line
			(start -1.4351 -0.7747)
			(end 1.4351 -0.7747)
			(stroke
				(width 0.1524)
				(type default)
			)
			(layer "F.SilkS")
		)
		(fp_line
			(start -1.4351 0.7747)
			(end -1.4351 -0.7747)
			(stroke
				(width 0.1524)
				(type default)
			)
			(layer "F.SilkS")
		)
		(fp_line
			(start 1.4351 -0.7747)
			(end 1.4351 0.7747)
			(stroke
				(width 0.1524)
				(type default)
			)
			(layer "F.SilkS")
		)
		(fp_line
			(start 1.4351 0.7747)
			(end -1.4351 0.7747)
			(stroke
				(width 0.1524)
				(type default)
			)
			(layer "F.SilkS")
		)
		(fp_rect
			(start -2.0193 1.0287)
			(end 1.6891 -1.0287)
			(stroke
				(width 0)
				(type default)
			)
			(fill no)
			(layer "F.CrtYd")
		)
		(fp_poly
			(pts
				(xy -2.0193 -1.0287) (xy -2.0193 1.0287) (xy 1.6891 1.0287) (xy 1.6891 -1.0287)
			)
			(stroke
				(width 0)
				(type default)
			)
			(fill no)
			(layer "F.Fab")
		)
		(pad "1" smd rect
			(at -0.7112 0)
			(size 0.9398 1.0668)
			(layers "F.Cu" "F.Mask" "F.Paste")
			(net "DEBUG_CONSOLE_LED_0")
		)
		(pad "2" smd rect
			(at 0.7112 0)
			(size 0.9398 1.0668)
			(layers "F.Cu" "F.Mask" "F.Paste")
			(net "CONSOLE_LED_0")
		)
	)
	(footprint ""
		(layer "F.Cu")
		(at 215.361774 -1.396746 -90)
		(property "Reference" "R3725"
			(at 0 0 270)
			(layer "F.SilkS")
			(hide yes)
			(effects
				(font
					(size 1.27 1.27)
				)
			)
		)
		(property "Value" "1KR2F-3-GP"
			(at 0.064008 -3.993896 270)
			(unlocked yes)
			(layer "F.Fab")
			(hide yes)
			(effects
				(font
					(size 1.016 1.016)
					(thickness 0.1524)
				)
			)
		)
		(property "Device Type" "R402H16"
			(at 0.064008 -5.517896 270)
			(unlocked yes)
			(layer "F.Fab")
			(hide yes)
			(effects
				(font
					(size 1.016 1.016)
					(thickness 0.1524)
				)
			)
		)
		(duplicate_pad_numbers_are_jumpers no)
		(fp_line
			(start -0.508 -0.9398)
			(end -0.508 0.9398)
			(stroke
				(width 0.1524)
				(type default)
			)
			(layer "F.SilkS")
		)
		(fp_line
			(start 0.508 -0.9398)
			(end -0.508 -0.9398)
			(stroke
				(width 0.1524)
				(type default)
			)
			(layer "F.SilkS")
		)
		(fp_rect
			(start -0.508 0.9398)
			(end 0.508 -0.9398)
			(stroke
				(width 0)
				(type default)
			)
			(fill no)
			(layer "F.CrtYd")
		)
		(fp_rect
			(start -0.508 0.9398)
			(end 0.508 -0.9398)
			(stroke
				(width 0)
				(type default)
			)
			(fill no)
			(layer "F.Fab")
		)
		(pad "1" smd custom
			(at 0 -0.4445 270)
			(size 0.1397 0.1397)
			(layers "F.Cu" "F.Mask" "F.Paste")
			(net "HOST1_RST_N_R")
			(options
				(clearance outline)
				(anchor circle)
			)
			(primitives
				(gr_poly
					(pts
						(arc
							(start -0.1778 -0.2794)
							(mid -0.249642 -0.249642)
							(end -0.2794 -0.1778)
						)
						(arc
							(start -0.2794 0.1778)
							(mid -0.249642 0.249642)
							(end -0.1778 0.2794)
						)
						(arc
							(start 0.1778 0.2794)
							(mid 0.249642 0.249642)
							(end 0.2794 0.1778)
						)
						(arc
							(start 0.2794 -0.1778)
							(mid 0.249642 -0.249642)
							(end 0.1778 -0.2794)
						)
					)
					(width 0)
					(fill yes)
				)
			)
		)
		(pad "2" smd custom
			(at 0 0.4445 270)
			(size 0.1397 0.1397)
			(layers "F.Cu" "F.Mask" "F.Paste")
			(net "P3V3_STBY")
			(options
				(clearance outline)
				(anchor circle)
			)
			(primitives
				(gr_poly
					(pts
						(arc
							(start -0.1778 -0.2794)
							(mid -0.249642 -0.249642)
							(end -0.2794 -0.1778)
						)
						(arc
							(start -0.2794 0.1778)
							(mid -0.249642 0.249642)
							(end -0.1778 0.2794)
						)
						(arc
							(start 0.1778 0.2794)
							(mid 0.249642 0.249642)
							(end 0.2794 0.1778)
						)
						(arc
							(start 0.2794 -0.1778)
							(mid 0.249642 -0.249642)
							(end 0.1778 -0.2794)
						)
					)
					(width 0)
					(fill yes)
				)
			)
		)
	)
	(footprint ""
		(layer "F.Cu")
		(at 221.742 -13.4112 90)
		(property "Reference" "R7910"
			(at 0 0 90)
			(layer "F.SilkS")
			(hide yes)
			(effects
				(font
					(size 1.27 1.27)
				)
			)
		)
		(property "Value" "0R2J-2-GP"
			(at 0.064008 -3.993896 90)
			(unlocked yes)
			(layer "F.Fab")
			(hide yes)
			(effects
				(font
					(size 1.016 1.016)
					(thickness 0.1524)
				)
			)
		)
		(property "Device Type" "R402H16"
			(at 0.064008 -5.517896 90)
			(unlocked yes)
			(layer "F.Fab")
			(hide yes)
			(effects
				(font
					(size 1.016 1.016)
					(thickness 0.1524)
				)
			)
		)
		(duplicate_pad_numbers_are_jumpers no)
		(fp_line
			(start 0.508 -0.9398)
			(end -0.508 -0.9398)
			(stroke
				(width 0.1524)
				(type default)
			)
			(layer "F.SilkS")
		)
		(fp_line
			(start -0.508 -0.9398)
			(end -0.508 0.9398)
			(stroke
				(width 0.1524)
				(type default)
			)
			(layer "F.SilkS")
		)
		(fp_rect
			(start -0.508 0.9398)
			(end 0.508 -0.9398)
			(stroke
				(width 0)
				(type default)
			)
			(fill no)
			(layer "F.CrtYd")
		)
		(fp_rect
			(start -0.508 0.9398)
			(end 0.508 -0.9398)
			(stroke
				(width 0)
				(type default)
			)
			(fill no)
			(layer "F.Fab")
		)
		(pad "1" smd custom
			(at 0 -0.4445 90)
			(size 0.1397 0.1397)
			(layers "F.Cu" "F.Mask" "F.Paste")
			(net "U81_Y")
			(options
				(clearance outline)
				(anchor circle)
			)
			(primitives
				(gr_poly
					(pts
						(arc
							(start -0.1778 -0.2794)
							(mid -0.249642 -0.249642)
							(end -0.2794 -0.1778)
						)
						(arc
							(start -0.2794 0.1778)
							(mid -0.249642 0.249642)
							(end -0.1778 0.2794)
						)
						(arc
							(start 0.1778 0.2794)
							(mid 0.249642 0.249642)
							(end 0.2794 0.1778)
						)
						(arc
							(start 0.2794 -0.1778)
							(mid 0.249642 -0.249642)
							(end 0.1778 -0.2794)
						)
					)
					(width 0)
					(fill yes)
				)
			)
		)
		(pad "2" smd custom
			(at 0 0.4445 90)
			(size 0.1397 0.1397)
			(layers "F.Cu" "F.Mask" "F.Paste")
			(net "U82_MR#")
			(options
				(clearance outline)
				(anchor circle)
			)
			(primitives
				(gr_poly
					(pts
						(arc
							(start -0.1778 -0.2794)
							(mid -0.249642 -0.249642)
							(end -0.2794 -0.1778)
						)
						(arc
							(start -0.2794 0.1778)
							(mid -0.249642 0.249642)
							(end -0.1778 0.2794)
						)
						(arc
							(start 0.1778 0.2794)
							(mid 0.249642 0.249642)
							(end 0.2794 0.1778)
						)
						(arc
							(start 0.2794 -0.1778)
							(mid 0.249642 -0.249642)
							(end 0.1778 -0.2794)
						)
					)
					(width 0)
					(fill yes)
				)
			)
		)
	)
	(footprint ""
		(layer "F.Cu")
		(at 262.971534 -6.837934 90)
		(property "Reference" "R697"
			(at 0 0 90)
			(layer "F.SilkS")
			(hide yes)
			(effects
				(font
					(size 1.27 1.27)
				)
			)
		)
		(property "Value" "4K7R2F-GP"
			(at 0.064008 -3.993896 90)
			(unlocked yes)
			(layer "F.Fab")
			(hide yes)
			(effects
				(font
					(size 1.016 1.016)
					(thickness 0.1524)
				)
			)
		)
		(property "Device Type" "R402H16"
			(at 0.064008 -5.517896 90)
			(unlocked yes)
			(layer "F.Fab")
			(hide yes)
			(effects
				(font
					(size 1.016 1.016)
					(thickness 0.1524)
				)
			)
		)
		(duplicate_pad_numbers_are_jumpers no)
		(fp_line
			(start 0.508 -0.9398)
			(end -0.508 -0.9398)
			(stroke
				(width 0.1524)
				(type default)
			)
			(layer "F.SilkS")
		)
		(fp_line
			(start -0.508 -0.9398)
			(end -0.508 0.9398)
			(stroke
				(width 0.1524)
				(type default)
			)
			(layer "F.SilkS")
		)
		(fp_rect
			(start -0.508 0.9398)
			(end 0.508 -0.9398)
			(stroke
				(width 0)
				(type default)
			)
			(fill no)
			(layer "F.CrtYd")
		)
		(fp_rect
			(start -0.508 0.9398)
			(end 0.508 -0.9398)
			(stroke
				(width 0)
				(type default)
			)
			(fill no)
			(layer "F.Fab")
		)
		(pad "1" smd custom
			(at 0 -0.4445 90)
			(size 0.1397 0.1397)
			(layers "F.Cu" "F.Mask" "F.Paste")
			(net "PQ22_G")
			(options
				(clearance outline)
				(anchor circle)
			)
			(primitives
				(gr_poly
					(pts
						(arc
							(start -0.1778 -0.2794)
							(mid -0.249642 -0.249642)
							(end -0.2794 -0.1778)
						)
						(arc
							(start -0.2794 0.1778)
							(mid -0.249642 0.249642)
							(end -0.1778 0.2794)
						)
						(arc
							(start 0.1778 0.2794)
							(mid 0.249642 0.249642)
							(end 0.2794 0.1778)
						)
						(arc
							(start 0.2794 -0.1778)
							(mid 0.249642 -0.249642)
							(end 0.1778 -0.2794)
						)
					)
					(width 0)
					(fill yes)
				)
			)
		)
		(pad "2" smd custom
			(at 0 0.4445 90)
			(size 0.1397 0.1397)
			(layers "F.Cu" "F.Mask" "F.Paste")
			(net "P3V3_STBY")
			(options
				(clearance outline)
				(anchor circle)
			)
			(primitives
				(gr_poly
					(pts
						(arc
							(start -0.1778 -0.2794)
							(mid -0.249642 -0.249642)
							(end -0.2794 -0.1778)
						)
						(arc
							(start -0.2794 0.1778)
							(mid -0.249642 0.249642)
							(end -0.1778 0.2794)
						)
						(arc
							(start 0.1778 0.2794)
							(mid 0.249642 0.249642)
							(end 0.2794 0.1778)
						)
						(arc
							(start 0.2794 -0.1778)
							(mid 0.249642 -0.249642)
							(end 0.1778 -0.2794)
						)
					)
					(width 0)
					(fill yes)
				)
			)
		)
	)
)
